FILE_TYPE = MACRO_DRAWING;
SET COLOR_WIRE YELLOW;
SET COLOR_PROP MONO;
SET COLOR_DOT WHITE;
SET COLOR_ARC YELLOW;
SET COLOR_BODY GREEN;
SET COLOR_NOTE MONO;
SET PROP_DISPLAY VALUE;
SET PAGE_NUMBER P262;
FORCEADD INTEL_CORP_BPAGE..1
(-1375 1800);
FORCEPROP 1 LAST CDS_CON_LAST_MODIFIED Fri Jun 16 17:49:39 2017
J 0
(-2800 2125);
PAINT ORANGE (-2800 2125);
DISPLAY INVISIBLE (-2800 2125);
FORCEPROP 1 LAST CUSTOM_TXT_CDS <CURRENT_DESIGN_SHEET> OF <TOTAL_DESIGN_SHEETS>
J 0
(-1875 1825);
PAINT ORANGE (-1875 1825);
FORCEPROP 2 LAST CUSTOM_TXT_CDS <XR_PAGE_TITLE>
J 0
(-9265 7050);
DISPLAY 0.638298 (-9265 7050);
PAINT PINK (-9265 7050);
DISPLAY INVISIBLE (-9265 7050);
FORCEPROP 2 LAST CUSTOM_TXT_CDS <CON_LAST_MODIFIED>
J 0
(-5375 1900);
PAINT ORANGE (-5375 1900);
FORCEPROP 1 LAST SCH_TITLE BUTTON BLOCK DIAGRAM
J 0
(-9325 1850);
DISPLAY 2.468085 (-9325 1850);
PAINT ORANGE (-9325 1850);
FORCEPROP 2 LAST PAGE_BORDER TRUE
J 0
(-9265 7050);
DISPLAY 0.638298 (-9265 7050);
PAINT PINK (-9265 7050);
DISPLAY INVISIBLE (-9265 7050);
FORCEPROP 2 LAST CDS_LIB mstr_symbols
J 0
(-1375 1800);
PAINT MONO (-1375 1800);
DISPLAY INVISIBLE (-1375 1800);
FORCEPROP 1 LAST COMMENT_BODY TRUE
J 0
(-1363 1812);
DISPLAY 0.468085 (-1363 1812);
PAINT GREEN (-1363 1812);
DISPLAY INVISIBLE (-1363 1812);
FORCEPROP 2 LAST CDS_XR_PAGE_TITLE CR-266 : @BASEBOARD_FAB2_LIB.BASEBOARD_FAB2(SCH_1):PAGE266
J 0
(-9265 7050);
DISPLAY 0.638298 (-9265 7050);
PAINT PINK (-9265 7050);
DISPLAY INVISIBLE (-9265 7050);
FORCENOTE
$CDS_IMAGE|Function_block_diagram_1_0330_J.jpg|8336|5000
(-5325 4450) 0;
DISPLAY LEFT (-5325 4450);
QUIT
